# BASEBOARD_FAB2 (Tioga Pass) — schematic netlist excerpt (pin names and nets, part order shuffled) for the footprints in the layout excerpt that follows; sources: Cadence DE-HDL packaged netlist, KiCad conversion of Wiwynn_Tioga_Pass_MB.brd

R7D28  RES  0.0 5% CHIP  pkg 0402  page 92 : A = H_CPU1_MSMI_G_N ; B = H_CPU_MSMI_G_N
CR10W1  DIODE  SDMK0340L IC  pkg SM  page 251 : C = PUMP_TACH_D ; A = PUMP_TACH_R

(kicad_pcb
	(version 20260206)
	(generator "pcbnew")
	(generator_version "10.0")
	(general
		(thickness 1.6)
		(legacy_teardrops no)
	)
	(paper "A4")
	(title_block
		(title "Wiwynn_Tioga_Pass_MB.brd")
		(comment 1 "Tioga Pass / footprints 242-243 of 4770")
	)
	(layers
		(0 "F.Cu" signal "TOP")
		(4 "In1.Cu" signal "L2GND")
		(6 "In2.Cu" signal "L3")
		(8 "In3.Cu" signal "L4GND")
		(10 "In4.Cu" signal "L5")
		(12 "In5.Cu" signal "L6GND")
		(14 "In6.Cu" signal "L7VCC")
		(16 "In7.Cu" signal "L8VCC")
		(18 "In8.Cu" signal "L9GND")
		(20 "In9.Cu" signal "L10")
		(22 "In10.Cu" signal "L11GND")
		(24 "In11.Cu" signal "L12")
		(26 "In12.Cu" signal "L13GND")
		(2 "B.Cu" signal "BOTTOM")
		(9 "F.Adhes" user "F.Adhesive")
		(11 "B.Adhes" user "B.Adhesive")
		(13 "F.Paste" user "Package Geometry/Pastemask Top")
		(15 "B.Paste" user "Package Geometry/Pastemask Bottom")
		(5 "F.SilkS" user "Ref Des/Silkscreen Top")
		(7 "B.SilkS" user "Ref Des/Silkscreen Bottom")
		(1 "F.Mask" user "Board Geometry/Soldermask Top")
		(3 "B.Mask" user "Board Geometry/Soldermask Bottom")
		(17 "Dwgs.User" user "User.Drawings")
		(19 "Cmts.User" user "User.Comments")
		(21 "Eco1.User" user "User.Eco1")
		(23 "Eco2.User" user "User.Eco2")
		(25 "Edge.Cuts" user "Board Geometry/Outline")
		(27 "Margin" user)
		(31 "F.CrtYd" user "Package Geometry/Place Bound Top")
		(29 "B.CrtYd" user "Package Geometry/Place Bound Bottom")
		(35 "F.Fab" user "Ref Des/Assembly Top")
		(33 "B.Fab" user "Ref Des/Assembly Bottom")
	)
	(footprint ""
		(layer "F.Cu")
		(at 383.14757 -78.902814 90)
		(property "Reference" "R7D28"
			(at 0 0 90)
			(layer "F.SilkS")
			(hide yes)
			(effects
				(font
					(size 1.27 1.27)
				)
			)
		)
		(property "Value" ""
			(at 0 0 90)
			(layer "F.Fab")
			(effects
				(font
					(size 1.27 1.27)
				)
			)
		)
		(duplicate_pad_numbers_are_jumpers no)
		(fp_poly
			(pts
				(xy -0.2794 -0.1016) (xy 0.2794 -0.1016) (xy 0.2794 0.9906) (xy -0.2794 0.9906)
			)
			(stroke
				(width 0)
				(type default)
			)
			(fill no)
			(layer "F.CrtYd")
		)
		(fp_line
			(start 0.2794 -0.1016)
			(end -0.2794 -0.1016)
			(stroke
				(width 0.1)
				(type default)
			)
			(layer "F.Fab")
		)
		(fp_line
			(start -0.2794 -0.1016)
			(end -0.2794 0.9906)
			(stroke
				(width 0.1)
				(type default)
			)
			(layer "F.Fab")
		)
		(fp_line
			(start 0.2794 0.9906)
			(end 0.2794 -0.1016)
			(stroke
				(width 0.1)
				(type default)
			)
			(layer "F.Fab")
		)
		(fp_line
			(start -0.2794 0.9906)
			(end 0.2794 0.9906)
			(stroke
				(width 0.1)
				(type default)
			)
			(layer "F.Fab")
		)
		(pad "1" smd rect
			(at 0 0 90)
			(size 0.508 0.508)
			(layers "F.Cu" "F.Mask" "F.Paste")
			(net "H_CPU1_MSMI_G_N")
		)
		(pad "2" smd rect
			(at 0 0.889 90)
			(size 0.508 0.508)
			(layers "F.Cu" "F.Mask" "F.Paste")
			(net "H_CPU_MSMI_G_N")
		)
		(zone
			(layer "F.Cu")
			(hatch none 0.5)
			(connect_pads
				(clearance 0)
			)
			(min_thickness 0.25)
			(keepout
				(tracks allowed)
				(vias not_allowed)
				(pads allowed)
				(copperpour not_allowed)
				(footprints allowed)
			)
			(placement
				(enabled no)
				(sheetname "")
			)
			(fill
				(thermal_gap 0.5)
				(thermal_bridge_width 0.5)
				(island_removal_mode 0)
			)
			(polygon
				(pts
					(xy 383.40157 -78.648814) (xy 383.40157 -79.156814) (xy 383.78257 -79.156814) (xy 383.78257 -78.648814)
				)
			)
		)
		(zone
			(layer "F.Cu")
			(hatch none 0.5)
			(connect_pads
				(clearance 0)
			)
			(min_thickness 0.25)
			(keepout
				(tracks not_allowed)
				(vias allowed)
				(pads allowed)
				(copperpour not_allowed)
				(footprints allowed)
			)
			(placement
				(enabled no)
				(sheetname "")
			)
			(fill
				(thermal_gap 0.5)
				(thermal_bridge_width 0.5)
				(island_removal_mode 0)
			)
			(polygon
				(pts
					(xy 383.78257 -78.648814) (xy 383.78257 -79.156814) (xy 383.40157 -79.156814) (xy 383.40157 -78.648814)
				)
			)
		)
	)
	(footprint ""
		(layer "F.Cu")
		(at 438.912 -20.828)
		(property "Reference" "CR10W1"
			(at 1.06934 -0.39116 270)
			(unlocked yes)
			(layer "F.SilkS")
			(effects
				(font
					(size 0.4064 0.254)
					(thickness 0.1524)
				)
				(justify left)
			)
		)
		(property "Value" ""
			(at 0 0 0)
			(layer "F.Fab")
			(effects
				(font
					(size 1.27 1.27)
				)
			)
		)
		(duplicate_pad_numbers_are_jumpers no)
		(fp_line
			(start -1.3843 0.038862)
			(end -0.903478 -0.794004)
			(stroke
				(width 0.1524)
				(type default)
			)
			(layer "F.SilkS")
		)
		(fp_line
			(start -0.903478 -1.917446)
			(end -0.903478 -0.794004)
			(stroke
				(width 0.1524)
				(type default)
			)
			(layer "F.SilkS")
		)
		(fp_line
			(start -0.903478 -0.794004)
			(end -0.422656 0.038862)
			(stroke
				(width 0.1524)
				(type default)
			)
			(layer "F.SilkS")
		)
		(fp_line
			(start -0.903478 0.038862)
			(end -1.3843 0.038862)
			(stroke
				(width 0.1524)
				(type default)
			)
			(layer "F.SilkS")
		)
		(fp_line
			(start -0.903478 0.950468)
			(end -0.903478 0.038862)
			(stroke
				(width 0.1524)
				(type default)
			)
			(layer "F.SilkS")
		)
		(fp_line
			(start -0.422656 -0.794004)
			(end -1.3843 -0.794004)
			(stroke
				(width 0.1524)
				(type default)
			)
			(layer "F.SilkS")
		)
		(fp_line
			(start -0.422656 0.038862)
			(end -0.903478 0.038862)
			(stroke
				(width 0.1524)
				(type default)
			)
			(layer "F.SilkS")
		)
		(fp_poly
			(pts
				(xy -0.67437 0.24384) (xy -0.67437 2.04216) (xy 0.67437 2.04216) (xy 0.67437 0.24384)
			)
			(stroke
				(width 0)
				(type default)
			)
			(fill no)
			(layer "F.CrtYd")
		)
		(fp_line
			(start -1.3843 0.038862)
			(end -0.903478 -0.794004)
			(stroke
				(width 0.1)
				(type default)
			)
			(layer "F.Fab")
		)
		(fp_line
			(start -0.903478 -0.794004)
			(end -0.903478 -1.917446)
			(stroke
				(width 0.1)
				(type default)
			)
			(layer "F.Fab")
		)
		(fp_line
			(start -0.903478 -0.794004)
			(end -0.422656 0.038862)
			(stroke
				(width 0.1)
				(type default)
			)
			(layer "F.Fab")
		)
		(fp_line
			(start -0.903478 0.038862)
			(end -0.903478 0.950468)
			(stroke
				(width 0.1)
				(type default)
			)
			(layer "F.Fab")
		)
		(fp_line
			(start -0.67437 0.24384)
			(end -0.67437 2.04216)
			(stroke
				(width 0.1)
				(type default)
			)
			(layer "F.Fab")
		)
		(fp_line
			(start -0.67437 2.04216)
			(end 0.67437 2.04216)
			(stroke
				(width 0.1)
				(type default)
			)
			(layer "F.Fab")
		)
		(fp_line
			(start -0.422656 -0.794004)
			(end -1.3843 -0.794004)
			(stroke
				(width 0.1)
				(type default)
			)
			(layer "F.Fab")
		)
		(fp_line
			(start -0.422656 0.038862)
			(end -1.3843 0.038862)
			(stroke
				(width 0.1)
				(type default)
			)
			(layer "F.Fab")
		)
		(fp_line
			(start 0.67437 0.24384)
			(end -0.67437 0.24384)
			(stroke
				(width 0.1)
				(type default)
			)
			(layer "F.Fab")
		)
		(fp_line
			(start 0.67437 2.04216)
			(end 0.67437 0.24384)
			(stroke
				(width 0.1)
				(type default)
			)
			(layer "F.Fab")
		)
		(pad "1" smd rect
			(at 0 0)
			(size 0.4064 1.016)
			(layers "F.Cu" "F.Mask" "F.Paste")
			(net "PUMP_TACH_D")
		)
		(pad "2" smd rect
			(at 0 2.286)
			(size 0.4064 1.016)
			(layers "F.Cu" "F.Mask" "F.Paste")
			(net "PUMP_TACH_R")
		)
	)
)
